(kicad_pcb
	(version 20241229)
	(generator "pcbnew")
	(generator_version "9.0")
	(general
		(thickness 1.61)
		(legacy_teardrops no)
	)
	(paper "A3")
	(title_block
		(title "SO-DIMM DDR5 Tester")
		(date "2025-11-26")
		(rev "1.3.0")
		(comment 9 "footprints 123-127 of 627")
	)
	(layers
		(0 "F.Cu" signal)
		(4 "In1.Cu" power)
		(6 "In2.Cu" mixed)
		(8 "In3.Cu" power)
		(10 "In4.Cu" mixed)
		(12 "In5.Cu" power)
		(14 "In6.Cu" mixed)
		(16 "In7.Cu" power)
		(18 "In8.Cu" power)
		(20 "In9.Cu" mixed)
		(22 "In10.Cu" power)
		(2 "B.Cu" signal)
		(9 "F.Adhes" user "F.Adhesive")
		(11 "B.Adhes" user "B.Adhesive")
		(13 "F.Paste" user)
		(15 "B.Paste" user)
		(5 "F.SilkS" user "F.Silkscreen")
		(7 "B.SilkS" user "B.Silkscreen")
		(1 "F.Mask" user)
		(3 "B.Mask" user)
		(17 "Dwgs.User" user "User.Drawings")
		(19 "Cmts.User" user "User.Comments")
		(21 "Eco1.User" user "User.Eco1")
		(23 "Eco2.User" user "User.Eco2")
		(25 "Edge.Cuts" user)
		(27 "Margin" user)
		(31 "F.CrtYd" user "F.Courtyard")
		(29 "B.CrtYd" user "B.Courtyard")
		(35 "F.Fab" user)
		(33 "B.Fab" user)
	)
	(footprint "antmicro-footprints:C_0402_1005Metric"
		(layer "F.Cu")
		(at 183.55 149.675)
		(descr "Capacitor SMD 0402")
		(tags "capacitor SMD 0402")
		(property "Reference" "C207"
			(at 0 -0.699 0)
			(layer "F.SilkS")
			(hide yes)
			(effects
				(font
					(size 0.7 0.7)
					(thickness 0.15)
				)
				(justify left bottom)
			)
		)
		(property "Value" "C_10u_6.3V_0402"
			(at -1.022927 2.155213 0)
			(layer "F.Fab")
			(effects
				(font
					(size 0.7 0.7)
					(thickness 0.15)
				)
				(justify left bottom)
			)
		)
		(property "Datasheet" "https://www.murata.com/products/productdetail?partno=GRM155R60J106ME15%23"
			(at 0 0 0)
			(layer "F.Fab")
			(hide yes)
			(effects
				(font
					(size 1.27 1.27)
					(thickness 0.15)
				)
			)
		)
		(property "Author" "Antmicro"
			(at 0 0 0)
			(layer "F.Fab")
			(hide yes)
			(effects
				(font
					(size 1 1)
					(thickness 0.15)
				)
			)
		)
		(property "Dielectric" "X5R"
			(at 0 0 0)
			(layer "F.Fab")
			(hide yes)
			(effects
				(font
					(size 1 1)
					(thickness 0.15)
				)
			)
		)
		(property "License" "Apache-2.0"
			(at 0 0 0)
			(layer "F.Fab")
			(hide yes)
			(effects
				(font
					(size 1 1)
					(thickness 0.15)
				)
			)
		)
		(property "MPN" "GRM155R60J106ME15D"
			(at 0 0 0)
			(layer "F.Fab")
			(hide yes)
			(effects
				(font
					(size 1 1)
					(thickness 0.15)
				)
			)
		)
		(property "Manufacturer" "Murata"
			(at 0 0 0)
			(layer "F.Fab")
			(hide yes)
			(effects
				(font
					(size 1 1)
					(thickness 0.15)
				)
			)
		)
		(property "Val" "10u"
			(at 0 0 0)
			(layer "F.Fab")
			(hide yes)
			(effects
				(font
					(size 1 1)
					(thickness 0.15)
				)
			)
		)
		(property "Voltage" "6.3V"
			(at 0 0 0)
			(layer "F.Fab")
			(hide yes)
			(effects
				(font
					(size 1 1)
					(thickness 0.15)
				)
			)
		)
		(sheetname "/Supply/")
		(sheetfile "supply.kicad_sch")
		(attr smd)
		(fp_rect
			(start -0.9659 -0.481258)
			(end 0.9649 0.458742)
			(stroke
				(width 0.05)
				(type solid)
			)
			(fill no)
			(layer "F.CrtYd")
		)
		(fp_line
			(start -0.499 -0.25)
			(end 0.499 -0.25)
			(stroke
				(width 0.15)
				(type solid)
			)
			(layer "F.Fab")
		)
		(fp_line
			(start -0.499 0.248)
			(end -0.499 -0.25)
			(stroke
				(width 0.15)
				(type solid)
			)
			(layer "F.Fab")
		)
		(fp_line
			(start 0.499 -0.25)
			(end 0.499 0.248)
			(stroke
				(width 0.15)
				(type solid)
			)
			(layer "F.Fab")
		)
		(fp_line
			(start 0.499 0.248)
			(end -0.499 0.248)
			(stroke
				(width 0.15)
				(type solid)
			)
			(layer "F.Fab")
		)
		(pad "1" smd roundrect
			(at -0.484 0)
			(size 0.59 0.64)
			(layers "F.Cu" "F.Mask" "F.Paste")
			(roundrect_rratio 0.25)
			(net 1 "GND")
			(pintype "passive")
		)
		(pad "2" smd roundrect
			(at 0.484 0)
			(size 0.59 0.64)
			(layers "F.Cu" "F.Mask" "F.Paste")
			(roundrect_rratio 0.25)
			(net 200 "+3V3")
			(pintype "passive")
		)
	)
	(footprint "antmicro-footprints:R_0402_1005Metric"
		(layer "F.Cu")
		(at 195.795501 179.4105 180)
		(descr "Resistor SMD 0402")
		(tags "resistor SMD 0402")
		(property "Reference" "R153"
			(at 4.045501 -0.3395 180)
			(layer "F.SilkS")
			(effects
				(font
					(size 0.7 0.7)
					(thickness 0.15)
				)
				(justify left bottom)
			)
		)
		(property "Value" "R_0R_0402"
			(at -1.011843 1.772047 180)
			(layer "F.Fab")
			(effects
				(font
					(size 0.7 0.7)
					(thickness 0.15)
				)
				(justify left bottom)
			)
		)
		(property "Datasheet" "https://industrial.panasonic.com/cdbs/www-data/pdf/RDA0000/AOA0000C301.pdf"
			(at 0 0 180)
			(layer "F.Fab")
			(hide yes)
			(effects
				(font
					(size 1.27 1.27)
					(thickness 0.15)
				)
			)
		)
		(property "Author" "Antmicro"
			(at 391.591002 358.821 0)
			(layer "F.Fab")
			(hide yes)
			(effects
				(font
					(size 1 1)
					(thickness 0.15)
				)
			)
		)
		(property "Current" "1A"
			(at 391.591002 358.821 0)
			(layer "F.Fab")
			(hide yes)
			(effects
				(font
					(size 1 1)
					(thickness 0.15)
				)
			)
		)
		(property "License" "Apache-2.0"
			(at 391.591002 358.821 0)
			(layer "F.Fab")
			(hide yes)
			(effects
				(font
					(size 1 1)
					(thickness 0.15)
				)
			)
		)
		(property "MPN" "ERJ2GE0R00X"
			(at 391.591002 358.821 0)
			(layer "F.Fab")
			(hide yes)
			(effects
				(font
					(size 1 1)
					(thickness 0.15)
				)
			)
		)
		(property "Manufacturer" "Panasonic"
			(at 391.591002 358.821 0)
			(layer "F.Fab")
			(hide yes)
			(effects
				(font
					(size 1 1)
					(thickness 0.15)
				)
			)
		)
		(property "Tolerance" ""
			(at 391.591002 358.821 0)
			(layer "F.Fab")
			(hide yes)
			(effects
				(font
					(size 1 1)
					(thickness 0.15)
				)
			)
		)
		(property "Val" "0R"
			(at 391.591002 358.821 0)
			(layer "F.Fab")
			(hide yes)
			(effects
				(font
					(size 1 1)
					(thickness 0.15)
				)
			)
		)
		(sheetname "/Supply/")
		(sheetfile "supply.kicad_sch")
		(attr smd)
		(fp_rect
			(start -0.93 -0.47)
			(end 0.93 0.47)
			(stroke
				(width 0.05)
				(type solid)
			)
			(fill no)
			(layer "F.CrtYd")
		)
		(fp_rect
			(start -0.5 -0.25)
			(end 0.5 0.25)
			(stroke
				(width 0.15)
				(type solid)
			)
			(fill no)
			(layer "F.Fab")
		)
		(pad "1" smd roundrect
			(at -0.485 0 180)
			(size 0.59 0.64)
			(layers "F.Cu" "F.Mask" "F.Paste")
			(roundrect_rratio 0.25)
			(net 211 "/Supply/FB2")
			(pintype "passive")
		)
		(pad "2" smd roundrect
			(at 0.485 0 180)
			(size 0.59 0.64)
			(layers "F.Cu" "F.Mask" "F.Paste")
			(roundrect_rratio 0.25)
			(net 51 "/Supply/1V8_local")
			(pintype "passive")
		)
	)
	(footprint "antmicro-footprints:R_0402_1005Metric"
		(layer "F.Cu")
		(at 202.881001 163.472 90)
		(descr "Resistor SMD 0402")
		(tags "resistor SMD 0402")
		(property "Reference" "R166"
			(at 0.972 0.368999 90)
			(layer "F.SilkS")
			(effects
				(font
					(size 0.7 0.7)
					(thickness 0.15)
				)
				(justify left bottom)
			)
		)
		(property "Value" "R_0R_0402"
			(at -1.011843 1.772047 90)
			(layer "F.Fab")
			(effects
				(font
					(size 0.7 0.7)
					(thickness 0.15)
				)
				(justify left bottom)
			)
		)
		(property "Datasheet" "https://industrial.panasonic.com/cdbs/www-data/pdf/RDA0000/AOA0000C301.pdf"
			(at 0 0 90)
			(layer "F.Fab")
			(hide yes)
			(effects
				(font
					(size 1.27 1.27)
					(thickness 0.15)
				)
			)
		)
		(property "Author" "Antmicro"
			(at 366.353001 -39.409001 0)
			(layer "F.Fab")
			(hide yes)
			(effects
				(font
					(size 1 1)
					(thickness 0.15)
				)
			)
		)
		(property "Current" "1A"
			(at 366.353001 -39.409001 0)
			(layer "F.Fab")
			(hide yes)
			(effects
				(font
					(size 1 1)
					(thickness 0.15)
				)
			)
		)
		(property "License" "Apache-2.0"
			(at 366.353001 -39.409001 0)
			(layer "F.Fab")
			(hide yes)
			(effects
				(font
					(size 1 1)
					(thickness 0.15)
				)
			)
		)
		(property "MPN" "ERJ2GE0R00X"
			(at 366.353001 -39.409001 0)
			(layer "F.Fab")
			(hide yes)
			(effects
				(font
					(size 1 1)
					(thickness 0.15)
				)
			)
		)
		(property "Manufacturer" "Panasonic"
			(at 366.353001 -39.409001 0)
			(layer "F.Fab")
			(hide yes)
			(effects
				(font
					(size 1 1)
					(thickness 0.15)
				)
			)
		)
		(property "Tolerance" ""
			(at 366.353001 -39.409001 0)
			(layer "F.Fab")
			(hide yes)
			(effects
				(font
					(size 1 1)
					(thickness 0.15)
				)
			)
		)
		(property "Val" "0R"
			(at 366.353001 -39.409001 0)
			(layer "F.Fab")
			(hide yes)
			(effects
				(font
					(size 1 1)
					(thickness 0.15)
				)
			)
		)
		(sheetname "/Supply/")
		(sheetfile "supply.kicad_sch")
		(attr smd)
		(fp_rect
			(start -0.93 -0.47)
			(end 0.93 0.47)
			(stroke
				(width 0.05)
				(type solid)
			)
			(fill no)
			(layer "F.CrtYd")
		)
		(fp_rect
			(start -0.5 -0.25)
			(end 0.5 0.25)
			(stroke
				(width 0.15)
				(type solid)
			)
			(fill no)
			(layer "F.Fab")
		)
		(pad "1" smd roundrect
			(at -0.485 0 90)
			(size 0.59 0.64)
			(layers "F.Cu" "F.Mask" "F.Paste")
			(roundrect_rratio 0.25)
			(net 217 "/Supply/FB7")
			(pintype "passive")
		)
		(pad "2" smd roundrect
			(at 0.485 0 90)
			(size 0.59 0.64)
			(layers "F.Cu" "F.Mask" "F.Paste")
			(roundrect_rratio 0.25)
			(net 53 "/Supply/1V1_local")
			(pintype "passive")
		)
	)
	(footprint "antmicro-footprints:C_0603_1608Metric"
		(layer "F.Cu")
		(at 168.655502 192.614501 180)
		(descr "Capacitor SMD 0603")
		(tags "capacitor 0603")
		(property "Reference" "C215"
			(at -1.42757 -1.000252 180)
			(layer "F.SilkS")
			(hide yes)
			(effects
				(font
					(size 0.7 0.7)
					(thickness 0.15)
				)
				(justify left bottom)
			)
		)
		(property "Value" "C_22u_0603"
			(at -1.42757 1.770288 180)
			(layer "F.Fab")
			(effects
				(font
					(size 0.7 0.7)
					(thickness 0.15)
				)
				(justify left bottom)
			)
		)
		(property "Datasheet" "https://www.murata.com/products/productdetail?partno=GRM188R60J226MEA0%23"
			(at 0 0 180)
			(layer "F.Fab")
			(hide yes)
			(effects
				(font
					(size 1.27 1.27)
					(thickness 0.15)
				)
			)
		)
		(property "Author" "Antmicro"
			(at 337.311004 385.229002 0)
			(layer "F.Fab")
			(hide yes)
			(effects
				(font
					(size 1 1)
					(thickness 0.15)
				)
			)
		)
		(property "Dielectric" ""
			(at 337.311004 385.229002 0)
			(layer "F.Fab")
			(hide yes)
			(effects
				(font
					(size 1 1)
					(thickness 0.15)
				)
			)
		)
		(property "License" "Apache-2.0"
			(at 337.311004 385.229002 0)
			(layer "F.Fab")
			(hide yes)
			(effects
				(font
					(size 1 1)
					(thickness 0.15)
				)
			)
		)
		(property "MPN" "GRM188R60J226MEA0D"
			(at 337.311004 385.229002 0)
			(layer "F.Fab")
			(hide yes)
			(effects
				(font
					(size 1 1)
					(thickness 0.15)
				)
			)
		)
		(property "Manufacturer" "Murata"
			(at 337.311004 385.229002 0)
			(layer "F.Fab")
			(hide yes)
			(effects
				(font
					(size 1 1)
					(thickness 0.15)
				)
			)
		)
		(property "Val" "22u"
			(at 337.311004 385.229002 0)
			(layer "F.Fab")
			(hide yes)
			(effects
				(font
					(size 1 1)
					(thickness 0.15)
				)
			)
		)
		(property "Voltage" ""
			(at 337.311004 385.229002 0)
			(layer "F.Fab")
			(hide yes)
			(effects
				(font
					(size 1 1)
					(thickness 0.15)
				)
			)
		)
		(sheetname "/Supply/")
		(sheetfile "supply.kicad_sch")
		(attr smd)
		(fp_line
			(start -0.3 0.3)
			(end 0.3 0.3)
			(stroke
				(width 0.15)
				(type solid)
			)
			(layer "F.SilkS")
		)
		(fp_line
			(start -0.3 -0.3)
			(end 0.3 -0.3)
			(stroke
				(width 0.15)
				(type solid)
			)
			(layer "F.SilkS")
		)
		(fp_rect
			(start -1.24 -0.7)
			(end 1.24 0.7)
			(stroke
				(width 0.05)
				(type solid)
			)
			(fill no)
			(layer "F.CrtYd")
		)
		(fp_rect
			(start -0.8 -0.4)
			(end 0.8 0.4)
			(stroke
				(width 0.15)
				(type solid)
			)
			(fill no)
			(layer "F.Fab")
		)
		(pad "1" smd roundrect
			(at -0.7 0 180)
			(size 0.6 0.8)
			(layers "F.Cu" "F.Mask" "F.Paste")
			(roundrect_rratio 0.2)
			(net 1 "GND")
			(pintype "passive")
		)
		(pad "2" smd roundrect
			(at 0.7 0 180)
			(size 0.6 0.8)
			(layers "F.Cu" "F.Mask" "F.Paste")
			(roundrect_rratio 0.2)
			(net 78 "/Supply/1V0_REG")
			(pintype "passive")
		)
	)
	(footprint "antmicro-footprints:C_Pol_EIA-B"
		(layer "F.Cu")
		(at 165.4 186.6 90)
		(property "Reference" "C25"
			(at 0 -2.3 90)
			(layer "F.SilkS")
			(hide yes)
			(effects
				(font
					(size 0.7 0.7)
					(thickness 0.15)
				)
				(justify left bottom)
			)
		)
		(property "Value" "C_Pol_330u_6.3V_KEMET-T520-B"
			(at 0 2.85 90)
			(layer "F.Fab")
			(effects
				(font
					(size 0.7 0.7)
					(thickness 0.15)
				)
				(justify left bottom)
			)
		)
		(property "Datasheet" "https://content.kemet.com/datasheets/KEM_T2076_T52X-530.pdf"
			(at 0 0 90)
			(layer "F.Fab")
			(hide yes)
			(effects
				(font
					(size 1.27 1.27)
					(thickness 0.15)
				)
			)
		)
		(property "Author" "Antmicro"
			(at 352 21.2 0)
			(layer "F.Fab")
			(hide yes)
			(effects
				(font
					(size 1 1)
					(thickness 0.15)
				)
			)
		)
		(property "License" "Apache-2.0"
			(at 352 21.2 0)
			(layer "F.Fab")
			(hide yes)
			(effects
				(font
					(size 1 1)
					(thickness 0.15)
				)
			)
		)
		(property "MPN" "T520B337M006ATE040"
			(at 352 21.2 0)
			(layer "F.Fab")
			(hide yes)
			(effects
				(font
					(size 1 1)
					(thickness 0.15)
				)
			)
		)
		(property "Manufacturer" "KEMET"
			(at 352 21.2 0)
			(layer "F.Fab")
			(hide yes)
			(effects
				(font
					(size 1 1)
					(thickness 0.15)
				)
			)
		)
		(property "Val" "330u/6.3V"
			(at 352 21.2 0)
			(layer "F.Fab")
			(hide yes)
			(effects
				(font
					(size 1 1)
					(thickness 0.15)
				)
			)
		)
		(property "Voltage" "6.3V"
			(at 352 21.2 0)
			(layer "F.Fab")
			(hide yes)
			(effects
				(font
					(size 1 1)
					(thickness 0.15)
				)
			)
		)
		(sheetname "/FPGA power/")
		(sheetfile "fpga-power.kicad_sch")
		(attr smd)
		(fp_line
			(start -2.521 -1.676)
			(end -2.123 -1.676)
			(stroke
				(width 0.15)
				(type solid)
			)
			(layer "F.SilkS")
		)
		(fp_line
			(start -1.8 -1.6)
			(end 1.8 -1.6)
			(stroke
				(width 0.15)
				(type solid)
			)
			(layer "F.SilkS")
		)
		(fp_line
			(start -2.325 -1.475)
			(end -2.325 -1.878)
			(stroke
				(width 0.15)
				(type solid)
			)
			(layer "F.SilkS")
		)
		(fp_line
			(start 1.8 -1.3)
			(end 1.8 -1.6)
			(stroke
				(width 0.15)
				(type solid)
			)
			(layer "F.SilkS")
		)
		(fp_line
			(start -1.8 -1.3)
			(end -1.8 -1.6)
			(stroke
				(width 0.15)
				(type solid)
			)
			(layer "F.SilkS")
		)
		(fp_line
			(start 1.8 1.3)
			(end 1.8 1.6)
			(stroke
				(width 0.15)
				(type solid)
			)
			(layer "F.SilkS")
		)
		(fp_line
			(start -1.8 1.3)
			(end -1.8 1.6)
			(stroke
				(width 0.15)
				(type solid)
			)
			(layer "F.SilkS")
		)
		(fp_line
			(start 1.8 1.6)
			(end -1.8 1.6)
			(stroke
				(width 0.15)
				(type solid)
			)
			(layer "F.SilkS")
		)
		(fp_line
			(start 1.959 -1.75)
			(end -1.971 -1.75)
			(stroke
				(width 0.05)
				(type solid)
			)
			(layer "F.CrtYd")
		)
		(fp_line
			(start 1.959 -1.75)
			(end 1.959 -1.35)
			(stroke
				(width 0.05)
				(type solid)
			)
			(layer "F.CrtYd")
		)
		(fp_line
			(start -1.97 -1.75)
			(end -1.97 -1.35)
			(stroke
				(width 0.05)
				(type solid)
			)
			(layer "F.CrtYd")
		)
		(fp_line
			(start 2.399 -1.35)
			(end 1.959 -1.35)
			(stroke
				(width 0.05)
				(type solid)
			)
			(layer "F.CrtYd")
		)
		(fp_line
			(start 2.399 -1.35)
			(end 2.4 1.35)
			(stroke
				(width 0.05)
				(type solid)
			)
			(layer "F.CrtYd")
		)
		(fp_line
			(start -1.97 -1.35)
			(end -2.41 -1.35)
			(stroke
				(width 0.05)
				(type solid)
			)
			(layer "F.CrtYd")
		)
		(fp_line
			(start -2.411 -1.35)
			(end -2.41 1.35)
			(stroke
				(width 0.05)
				(type solid)
			)
			(layer "F.CrtYd")
		)
		(fp_line
			(start 2.4 1.35)
			(end 1.96 1.35)
			(stroke
				(width 0.05)
				(type solid)
			)
			(layer "F.CrtYd")
		)
		(fp_line
			(start 1.96 1.35)
			(end 1.96 1.75)
			(stroke
				(width 0.05)
				(type solid)
			)
			(layer "F.CrtYd")
		)
		(fp_line
			(start -1.97 1.35)
			(end -2.41 1.35)
			(stroke
				(width 0.05)
				(type solid)
			)
			(layer "F.CrtYd")
		)
		(fp_line
			(start -1.97 1.35)
			(end -1.97 1.75)
			(stroke
				(width 0.05)
				(type solid)
			)
			(layer "F.CrtYd")
		)
		(fp_line
			(start 1.96 1.75)
			(end -1.97 1.75)
			(stroke
				(width 0.05)
				(type solid)
			)
			(layer "F.CrtYd")
		)
		(fp_line
			(start -1.7 1.324)
			(end -1.551 1.475)
			(stroke
				(width 0.15)
				(type solid)
			)
			(layer "F.Fab")
		)
		(fp_rect
			(start -1.72 -1.5)
			(end 1.719 1.499)
			(stroke
				(width 0.15)
				(type solid)
			)
			(fill no)
			(layer "F.Fab")
		)
		(pad "1" smd roundrect
			(at -1.551 0 90)
			(size 1.2 2.2)
			(layers "F.Cu" "F.Mask" "F.Paste")
			(roundrect_rratio 0.1)
			(net 227 "+1V0")
			(pintype "passive")
		)
		(pad "2" smd roundrect
			(at 1.55 0 90)
			(size 1.2 2.2)
			(layers "F.Cu" "F.Mask" "F.Paste")
			(roundrect_rratio 0.1)
			(net 1 "GND")
			(pintype "passive")
		)
	)
)
